(kicad_pcb
	(version 20260206)
	(generator "pcbnew")
	(generator_version "10.0")
	(general
		(thickness 1.6)
		(legacy_teardrops no)
	)
	(paper "A4")
	(title_block
		(title "12092022_DA0F0TFB6D0_F0T_FAN_BOARD_MP5048_D_brd_v02_OCP.brd")
		(comment 1 "Grand Teton / footprints 98-103 of 924")
	)
	(layers
		(0 "F.Cu" signal "TOP")
		(4 "In1.Cu" signal "GND")
		(6 "In2.Cu" signal "IN1")
		(8 "In3.Cu" signal "IN2")
		(10 "In4.Cu" signal "GND1")
		(2 "B.Cu" signal "BOTTOM")
		(9 "F.Adhes" user "F.Adhesive")
		(11 "B.Adhes" user "B.Adhesive")
		(13 "F.Paste" user "Package Geometry/Pastemask Top")
		(15 "B.Paste" user "Package Geometry/Pastemask Bottom")
		(5 "F.SilkS" user "Ref Des/Silkscreen Top")
		(7 "B.SilkS" user "Ref Des/Silkscreen Bottom")
		(1 "F.Mask" user "Board Geometry/Soldermask Top")
		(3 "B.Mask" user "Board Geometry/Soldermask Bottom")
		(17 "Dwgs.User" user "User.Drawings")
		(19 "Cmts.User" user "User.Comments")
		(21 "Eco1.User" user "User.Eco1")
		(23 "Eco2.User" user "User.Eco2")
		(25 "Edge.Cuts" user "Board Geometry/Outline")
		(27 "Margin" user)
		(31 "F.CrtYd" user "Package Geometry/Place Bound Top")
		(29 "B.CrtYd" user "Package Geometry/Place Bound Bottom")
		(35 "F.Fab" user "Ref Des/Assembly Top")
		(33 "B.Fab" user "Ref Des/Assembly Bottom")
	)
	(footprint ""
		(layer "F.Cu")
		(at 5.461 -189.992)
		(property "Reference" "R312"
			(at 0 0 0)
			(layer "F.SilkS")
			(hide yes)
			(effects
				(font
					(size 1.27 1.27)
				)
			)
		)
		(property "Value" ""
			(at 0 0 0)
			(layer "F.Fab")
			(effects
				(font
					(size 1.27 1.27)
				)
			)
		)
		(duplicate_pad_numbers_are_jumpers no)
		(fp_line
			(start -0.7874 -0.4064)
			(end 0.7874 -0.4064)
			(stroke
				(width 0.1524)
				(type default)
			)
			(layer "F.SilkS")
		)
		(fp_line
			(start -0.7874 0.4064)
			(end -0.7874 -0.4064)
			(stroke
				(width 0.1524)
				(type default)
			)
			(layer "F.SilkS")
		)
		(fp_line
			(start 0.7874 -0.4064)
			(end 0.7874 0.4064)
			(stroke
				(width 0.1524)
				(type default)
			)
			(layer "F.SilkS")
		)
		(fp_line
			(start 0.7874 0.4064)
			(end -0.7874 0.4064)
			(stroke
				(width 0.1524)
				(type default)
			)
			(layer "F.SilkS")
		)
		(fp_line
			(start -0.67945 -0.305054)
			(end -0.12065 -0.305054)
			(stroke
				(width 0.1)
				(type default)
			)
			(layer "F.Fab")
		)
		(fp_line
			(start -0.67945 0.3048)
			(end -0.67945 -0.305054)
			(stroke
				(width 0.1)
				(type default)
			)
			(layer "F.Fab")
		)
		(fp_line
			(start -0.12065 -0.305054)
			(end -0.12065 -0.2794)
			(stroke
				(width 0.1)
				(type default)
			)
			(layer "F.Fab")
		)
		(fp_line
			(start -0.12065 -0.2794)
			(end 0.12065 -0.2794)
			(stroke
				(width 0.1)
				(type default)
			)
			(layer "F.Fab")
		)
		(fp_line
			(start -0.12065 0.2794)
			(end -0.12065 0.3048)
			(stroke
				(width 0.1)
				(type default)
			)
			(layer "F.Fab")
		)
		(fp_line
			(start -0.12065 0.3048)
			(end -0.67945 0.3048)
			(stroke
				(width 0.1)
				(type default)
			)
			(layer "F.Fab")
		)
		(fp_line
			(start 0.120396 0.2794)
			(end -0.12065 0.2794)
			(stroke
				(width 0.1)
				(type default)
			)
			(layer "F.Fab")
		)
		(fp_line
			(start 0.120396 0.3048)
			(end 0.120396 0.2794)
			(stroke
				(width 0.1)
				(type default)
			)
			(layer "F.Fab")
		)
		(fp_line
			(start 0.12065 -0.3048)
			(end 0.67945 -0.3048)
			(stroke
				(width 0.1)
				(type default)
			)
			(layer "F.Fab")
		)
		(fp_line
			(start 0.12065 -0.2794)
			(end 0.12065 -0.3048)
			(stroke
				(width 0.1)
				(type default)
			)
			(layer "F.Fab")
		)
		(fp_line
			(start 0.67945 -0.3048)
			(end 0.67945 0.3048)
			(stroke
				(width 0.1)
				(type default)
			)
			(layer "F.Fab")
		)
		(fp_line
			(start 0.67945 0.3048)
			(end 0.120396 0.3048)
			(stroke
				(width 0.1)
				(type default)
			)
			(layer "F.Fab")
		)
		(pad "1" smd circle
			(at -0.40005 0)
			(size 0 0)
			(layers "F.Cu" "F.Mask" "F.Paste")
			(net "P3V3_AUX")
		)
		(pad "2" smd circle
			(at 0.40005 0)
			(size 0 0)
			(layers "F.Cu" "F.Mask" "F.Paste")
			(net "FRU_ADDR0")
		)
	)
	(footprint ""
		(layer "F.Cu")
		(at 16.520922 -291.5031)
		(property "Reference" "C2057"
			(at 0 0 0)
			(layer "F.SilkS")
			(hide yes)
			(effects
				(font
					(size 1.27 1.27)
				)
			)
		)
		(property "Value" ""
			(at 0 0 0)
			(layer "F.Fab")
			(effects
				(font
					(size 1.27 1.27)
				)
			)
		)
		(duplicate_pad_numbers_are_jumpers no)
		(fp_line
			(start -0.7874 -0.4064)
			(end 0.7874 -0.4064)
			(stroke
				(width 0.1524)
				(type default)
			)
			(layer "F.SilkS")
		)
		(fp_line
			(start -0.7874 0.4064)
			(end -0.7874 -0.4064)
			(stroke
				(width 0.1524)
				(type default)
			)
			(layer "F.SilkS")
		)
		(fp_line
			(start 0.7874 -0.4064)
			(end 0.7874 0.4064)
			(stroke
				(width 0.1524)
				(type default)
			)
			(layer "F.SilkS")
		)
		(fp_line
			(start 0.7874 0.4064)
			(end -0.7874 0.4064)
			(stroke
				(width 0.1524)
				(type default)
			)
			(layer "F.SilkS")
		)
		(fp_line
			(start -0.67945 -0.305054)
			(end -0.12065 -0.305054)
			(stroke
				(width 0.1)
				(type default)
			)
			(layer "F.Fab")
		)
		(fp_line
			(start -0.67945 0.3048)
			(end -0.67945 -0.305054)
			(stroke
				(width 0.1)
				(type default)
			)
			(layer "F.Fab")
		)
		(fp_line
			(start -0.12065 -0.305054)
			(end -0.12065 -0.2794)
			(stroke
				(width 0.1)
				(type default)
			)
			(layer "F.Fab")
		)
		(fp_line
			(start -0.12065 -0.2794)
			(end 0.12065 -0.2794)
			(stroke
				(width 0.1)
				(type default)
			)
			(layer "F.Fab")
		)
		(fp_line
			(start -0.12065 0.2794)
			(end -0.12065 0.3048)
			(stroke
				(width 0.1)
				(type default)
			)
			(layer "F.Fab")
		)
		(fp_line
			(start -0.12065 0.3048)
			(end -0.67945 0.3048)
			(stroke
				(width 0.1)
				(type default)
			)
			(layer "F.Fab")
		)
		(fp_line
			(start 0.120396 0.2794)
			(end -0.12065 0.2794)
			(stroke
				(width 0.1)
				(type default)
			)
			(layer "F.Fab")
		)
		(fp_line
			(start 0.120396 0.3048)
			(end 0.120396 0.2794)
			(stroke
				(width 0.1)
				(type default)
			)
			(layer "F.Fab")
		)
		(fp_line
			(start 0.12065 -0.3048)
			(end 0.67945 -0.3048)
			(stroke
				(width 0.1)
				(type default)
			)
			(layer "F.Fab")
		)
		(fp_line
			(start 0.12065 -0.2794)
			(end 0.12065 -0.3048)
			(stroke
				(width 0.1)
				(type default)
			)
			(layer "F.Fab")
		)
		(fp_line
			(start 0.67945 -0.3048)
			(end 0.67945 0.3048)
			(stroke
				(width 0.1)
				(type default)
			)
			(layer "F.Fab")
		)
		(fp_line
			(start 0.67945 0.3048)
			(end 0.120396 0.3048)
			(stroke
				(width 0.1)
				(type default)
			)
			(layer "F.Fab")
		)
		(pad "1" smd circle
			(at -0.40005 0)
			(size 0 0)
			(layers "F.Cu" "F.Mask" "F.Paste")
			(net "FAN_7_PWM_IL_R")
		)
		(pad "2" smd circle
			(at 0.40005 0)
			(size 0 0)
			(layers "F.Cu" "F.Mask" "F.Paste")
			(net "GND")
		)
	)
	(footprint ""
		(layer "F.Cu")
		(at 36.83 -110.363 90)
		(property "Reference" "R5410"
			(at 0 0 90)
			(layer "F.SilkS")
			(hide yes)
			(effects
				(font
					(size 1.27 1.27)
				)
			)
		)
		(property "Value" ""
			(at 0 0 90)
			(layer "F.Fab")
			(effects
				(font
					(size 1.27 1.27)
				)
			)
		)
		(duplicate_pad_numbers_are_jumpers no)
		(fp_line
			(start 0.7874 -0.4064)
			(end 0.7874 0.4064)
			(stroke
				(width 0.1524)
				(type default)
			)
			(layer "F.SilkS")
		)
		(fp_line
			(start -0.7874 -0.4064)
			(end 0.7874 -0.4064)
			(stroke
				(width 0.1524)
				(type default)
			)
			(layer "F.SilkS")
		)
		(fp_line
			(start 0.7874 0.4064)
			(end -0.7874 0.4064)
			(stroke
				(width 0.1524)
				(type default)
			)
			(layer "F.SilkS")
		)
		(fp_line
			(start -0.7874 0.4064)
			(end -0.7874 -0.4064)
			(stroke
				(width 0.1524)
				(type default)
			)
			(layer "F.SilkS")
		)
		(fp_line
			(start -0.12065 -0.305054)
			(end -0.12065 -0.2794)
			(stroke
				(width 0.1)
				(type default)
			)
			(layer "F.Fab")
		)
		(fp_line
			(start -0.67945 -0.305054)
			(end -0.12065 -0.305054)
			(stroke
				(width 0.1)
				(type default)
			)
			(layer "F.Fab")
		)
		(fp_line
			(start 0.67945 -0.3048)
			(end 0.67945 0.3048)
			(stroke
				(width 0.1)
				(type default)
			)
			(layer "F.Fab")
		)
		(fp_line
			(start 0.12065 -0.3048)
			(end 0.67945 -0.3048)
			(stroke
				(width 0.1)
				(type default)
			)
			(layer "F.Fab")
		)
		(fp_line
			(start 0.12065 -0.2794)
			(end 0.12065 -0.3048)
			(stroke
				(width 0.1)
				(type default)
			)
			(layer "F.Fab")
		)
		(fp_line
			(start -0.12065 -0.2794)
			(end 0.12065 -0.2794)
			(stroke
				(width 0.1)
				(type default)
			)
			(layer "F.Fab")
		)
		(fp_line
			(start 0.120396 0.2794)
			(end -0.12065 0.2794)
			(stroke
				(width 0.1)
				(type default)
			)
			(layer "F.Fab")
		)
		(fp_line
			(start -0.12065 0.2794)
			(end -0.12065 0.3048)
			(stroke
				(width 0.1)
				(type default)
			)
			(layer "F.Fab")
		)
		(fp_line
			(start 0.67945 0.3048)
			(end 0.120396 0.3048)
			(stroke
				(width 0.1)
				(type default)
			)
			(layer "F.Fab")
		)
		(fp_line
			(start 0.120396 0.3048)
			(end 0.120396 0.2794)
			(stroke
				(width 0.1)
				(type default)
			)
			(layer "F.Fab")
		)
		(fp_line
			(start -0.12065 0.3048)
			(end -0.67945 0.3048)
			(stroke
				(width 0.1)
				(type default)
			)
			(layer "F.Fab")
		)
		(fp_line
			(start -0.67945 0.3048)
			(end -0.67945 -0.305054)
			(stroke
				(width 0.1)
				(type default)
			)
			(layer "F.Fab")
		)
		(pad "1" smd rect
			(at -0.40005 0 270)
			(size 0.4572 0.508)
			(layers "F.Cu" "F.Mask" "F.Paste")
			(net "FAN_2_FAIL_LED_R_N")
		)
		(pad "2" smd rect
			(at 0.40005 0 270)
			(size 0.4572 0.508)
			(layers "F.Cu" "F.Mask" "F.Paste")
			(net "FAN_2_FAIL_R_LED_N")
		)
	)
	(footprint ""
		(layer "F.Cu")
		(at 32.893 -207.01)
		(property "Reference" "D274"
			(at -1.397 1.29667 0)
			(unlocked yes)
			(layer "F.SilkS")
			(effects
				(font
					(size 0.7874 0.5842)
					(thickness 0.1524)
				)
				(justify left)
			)
		)
		(property "Value" ""
			(at 0 0 0)
			(layer "F.Fab")
			(effects
				(font
					(size 1.27 1.27)
				)
			)
		)
		(duplicate_pad_numbers_are_jumpers no)
		(fp_line
			(start -0.854964 -0.450088)
			(end -0.854964 0.450088)
			(stroke
				(width 0.1524)
				(type default)
			)
			(layer "F.SilkS")
		)
		(fp_line
			(start -0.854964 0.450088)
			(end 0.925068 0.450088)
			(stroke
				(width 0.1524)
				(type default)
			)
			(layer "F.SilkS")
		)
		(fp_line
			(start 0.845058 0.4064)
			(end 0.845058 -0.381)
			(stroke
				(width 0.1524)
				(type default)
			)
			(layer "F.SilkS")
		)
		(fp_line
			(start 0.870458 -0.2794)
			(end 0.845058 0.4064)
			(stroke
				(width 0.1524)
				(type default)
			)
			(layer "F.SilkS")
		)
		(fp_line
			(start 0.94488 -0.450088)
			(end -0.854964 -0.450088)
			(stroke
				(width 0.1524)
				(type default)
			)
			(layer "F.SilkS")
		)
		(fp_line
			(start 0.94488 0.450088)
			(end 0.94488 -0.450088)
			(stroke
				(width 0.1524)
				(type default)
			)
			(layer "F.SilkS")
		)
		(fp_line
			(start -0.54991 -0.350012)
			(end -0.54991 0.350012)
			(stroke
				(width 0.1)
				(type default)
			)
			(layer "F.Fab")
		)
		(fp_line
			(start -0.54991 0.350012)
			(end 0.54991 0.350012)
			(stroke
				(width 0.1)
				(type default)
			)
			(layer "F.Fab")
		)
		(fp_line
			(start 0.54991 -0.350012)
			(end -0.54991 -0.350012)
			(stroke
				(width 0.1)
				(type default)
			)
			(layer "F.Fab")
		)
		(fp_line
			(start 0.54991 0.350012)
			(end 0.54991 -0.350012)
			(stroke
				(width 0.1)
				(type default)
			)
			(layer "F.Fab")
		)
		(fp_text user "+"
			(at -1.016 0.22225 180)
			(unlocked yes)
			(layer "F.SilkS")
			(effects
				(font
					(size 1.905 1.4224)
					(thickness 0.1524)
				)
				(justify left)
			)
		)
		(fp_text user "-"
			(at 1.651 -0.43815 180)
			(unlocked yes)
			(layer "F.SilkS")
			(effects
				(font
					(size 1.905 1.4224)
					(thickness 0.1524)
				)
				(justify left)
			)
		)
		(fp_text user "+"
			(at -0.808228 0.239014 180)
			(unlocked yes)
			(layer "F.Fab")
			(effects
				(font
					(size 1.905 1.4224)
					(thickness 0.1524)
				)
				(justify left)
			)
		)
		(fp_text user "-"
			(at 2.48539 0.239014 180)
			(unlocked yes)
			(layer "F.Fab")
			(effects
				(font
					(size 1.905 1.4224)
					(thickness 0.1524)
				)
				(justify left)
			)
		)
		(pad "A" smd rect
			(at -0.424942 0)
			(size 0.5588 0.6096)
			(layers "F.Cu" "F.Mask" "F.Paste")
			(net "GND")
		)
		(pad "C" smd rect
			(at 0.424942 0 180)
			(size 0.5588 0.6096)
			(layers "F.Cu" "F.Mask" "F.Paste")
			(net "FAN_1_PWM_IL_R")
		)
	)
	(footprint ""
		(layer "F.Cu")
		(at 13.335 -162.814 180)
		(property "Reference" "R5507"
			(at 0 0 180)
			(layer "F.SilkS")
			(hide yes)
			(effects
				(font
					(size 1.27 1.27)
				)
			)
		)
		(property "Value" ""
			(at 0 0 180)
			(layer "F.Fab")
			(effects
				(font
					(size 1.27 1.27)
				)
			)
		)
		(duplicate_pad_numbers_are_jumpers no)
		(fp_line
			(start 0.7874 0.4064)
			(end -0.7874 0.4064)
			(stroke
				(width 0.1524)
				(type default)
			)
			(layer "F.SilkS")
		)
		(fp_line
			(start 0.7874 -0.4064)
			(end 0.7874 0.4064)
			(stroke
				(width 0.1524)
				(type default)
			)
			(layer "F.SilkS")
		)
		(fp_line
			(start -0.7874 0.4064)
			(end -0.7874 -0.4064)
			(stroke
				(width 0.1524)
				(type default)
			)
			(layer "F.SilkS")
		)
		(fp_line
			(start -0.7874 -0.4064)
			(end 0.7874 -0.4064)
			(stroke
				(width 0.1524)
				(type default)
			)
			(layer "F.SilkS")
		)
		(fp_line
			(start 0.67945 0.3048)
			(end 0.120396 0.3048)
			(stroke
				(width 0.1)
				(type default)
			)
			(layer "F.Fab")
		)
		(fp_line
			(start 0.67945 -0.3048)
			(end 0.67945 0.3048)
			(stroke
				(width 0.1)
				(type default)
			)
			(layer "F.Fab")
		)
		(fp_line
			(start 0.12065 -0.2794)
			(end 0.12065 -0.3048)
			(stroke
				(width 0.1)
				(type default)
			)
			(layer "F.Fab")
		)
		(fp_line
			(start 0.12065 -0.3048)
			(end 0.67945 -0.3048)
			(stroke
				(width 0.1)
				(type default)
			)
			(layer "F.Fab")
		)
		(fp_line
			(start 0.120396 0.3048)
			(end 0.120396 0.2794)
			(stroke
				(width 0.1)
				(type default)
			)
			(layer "F.Fab")
		)
		(fp_line
			(start 0.120396 0.2794)
			(end -0.12065 0.2794)
			(stroke
				(width 0.1)
				(type default)
			)
			(layer "F.Fab")
		)
		(fp_line
			(start -0.12065 0.3048)
			(end -0.67945 0.3048)
			(stroke
				(width 0.1)
				(type default)
			)
			(layer "F.Fab")
		)
		(fp_line
			(start -0.12065 0.2794)
			(end -0.12065 0.3048)
			(stroke
				(width 0.1)
				(type default)
			)
			(layer "F.Fab")
		)
		(fp_line
			(start -0.12065 -0.2794)
			(end 0.12065 -0.2794)
			(stroke
				(width 0.1)
				(type default)
			)
			(layer "F.Fab")
		)
		(fp_line
			(start -0.12065 -0.305054)
			(end -0.12065 -0.2794)
			(stroke
				(width 0.1)
				(type default)
			)
			(layer "F.Fab")
		)
		(fp_line
			(start -0.67945 0.3048)
			(end -0.67945 -0.305054)
			(stroke
				(width 0.1)
				(type default)
			)
			(layer "F.Fab")
		)
		(fp_line
			(start -0.67945 -0.305054)
			(end -0.12065 -0.305054)
			(stroke
				(width 0.1)
				(type default)
			)
			(layer "F.Fab")
		)
		(pad "1" smd circle
			(at -0.40005 0 180)
			(size 0 0)
			(layers "F.Cu" "F.Mask" "F.Paste")
			(net "P3V3_AUX")
		)
		(pad "2" smd circle
			(at 0.40005 0 180)
			(size 0 0)
			(layers "F.Cu" "F.Mask" "F.Paste")
			(net "FAN_0_PRESENT_N")
		)
	)
	(footprint ""
		(layer "F.Cu")
		(at 37.846 -136.398 180)
		(property "Reference" "R5598"
			(at 0 0 180)
			(layer "F.SilkS")
			(hide yes)
			(effects
				(font
					(size 1.27 1.27)
				)
			)
		)
		(property "Value" ""
			(at 0 0 180)
			(layer "F.Fab")
			(effects
				(font
					(size 1.27 1.27)
				)
			)
		)
		(duplicate_pad_numbers_are_jumpers no)
		(fp_line
			(start 0.7874 0.4064)
			(end -0.7874 0.4064)
			(stroke
				(width 0.1524)
				(type default)
			)
			(layer "F.SilkS")
		)
		(fp_line
			(start 0.7874 -0.4064)
			(end 0.7874 0.4064)
			(stroke
				(width 0.1524)
				(type default)
			)
			(layer "F.SilkS")
		)
		(fp_line
			(start -0.7874 0.4064)
			(end -0.7874 -0.4064)
			(stroke
				(width 0.1524)
				(type default)
			)
			(layer "F.SilkS")
		)
		(fp_line
			(start -0.7874 -0.4064)
			(end 0.7874 -0.4064)
			(stroke
				(width 0.1524)
				(type default)
			)
			(layer "F.SilkS")
		)
		(fp_line
			(start 0.67945 0.3048)
			(end 0.120396 0.3048)
			(stroke
				(width 0.1)
				(type default)
			)
			(layer "F.Fab")
		)
		(fp_line
			(start 0.67945 -0.3048)
			(end 0.67945 0.3048)
			(stroke
				(width 0.1)
				(type default)
			)
			(layer "F.Fab")
		)
		(fp_line
			(start 0.12065 -0.2794)
			(end 0.12065 -0.3048)
			(stroke
				(width 0.1)
				(type default)
			)
			(layer "F.Fab")
		)
		(fp_line
			(start 0.12065 -0.3048)
			(end 0.67945 -0.3048)
			(stroke
				(width 0.1)
				(type default)
			)
			(layer "F.Fab")
		)
		(fp_line
			(start 0.120396 0.3048)
			(end 0.120396 0.2794)
			(stroke
				(width 0.1)
				(type default)
			)
			(layer "F.Fab")
		)
		(fp_line
			(start 0.120396 0.2794)
			(end -0.12065 0.2794)
			(stroke
				(width 0.1)
				(type default)
			)
			(layer "F.Fab")
		)
		(fp_line
			(start -0.12065 0.3048)
			(end -0.67945 0.3048)
			(stroke
				(width 0.1)
				(type default)
			)
			(layer "F.Fab")
		)
		(fp_line
			(start -0.12065 0.2794)
			(end -0.12065 0.3048)
			(stroke
				(width 0.1)
				(type default)
			)
			(layer "F.Fab")
		)
		(fp_line
			(start -0.12065 -0.2794)
			(end 0.12065 -0.2794)
			(stroke
				(width 0.1)
				(type default)
			)
			(layer "F.Fab")
		)
		(fp_line
			(start -0.12065 -0.305054)
			(end -0.12065 -0.2794)
			(stroke
				(width 0.1)
				(type default)
			)
			(layer "F.Fab")
		)
		(fp_line
			(start -0.67945 0.3048)
			(end -0.67945 -0.305054)
			(stroke
				(width 0.1)
				(type default)
			)
			(layer "F.Fab")
		)
		(fp_line
			(start -0.67945 -0.305054)
			(end -0.12065 -0.305054)
			(stroke
				(width 0.1)
				(type default)
			)
			(layer "F.Fab")
		)
		(pad "1" smd rect
			(at -0.40005 0)
			(size 0.4572 0.508)
			(layers "F.Cu" "F.Mask" "F.Paste")
			(net "FAN_0_TACH_IL")
		)
		(pad "2" smd rect
			(at 0.40005 0)
			(size 0.4572 0.508)
			(layers "F.Cu" "F.Mask" "F.Paste")
			(net "FAN_0_TACH_IL_R1")
		)
	)
)
